# BASEBOARD_FAB2 (Tioga Pass) — schematic netlist excerpt (pin names and nets, part order shuffled) for the footprints in the layout excerpt that follows; sources: Cadence DE-HDL packaged netlist, KiCad conversion of Wiwynn_Tioga_Pass_MB.brd

J1C1  DM-FCI-CONN76-8R-GP-U-01  pkg CONN-G4  page 182
  PCIE_RX_DP0  = P3E_CPU1_PE3_MP_RXN<8>
  GND1  = GND
  PCIE_RX_DP6  = P3E_CPU1_PE3_MP_RXP<14>
  FAN_TACH3  = GND
  MNG_TX_DP  = TP_IOA5
  \pmbus_alert#\  = GND
  PCIE_TX_DP3  = P3E_CPU1_PE3_MP_C_TXN<11>
  GND2  = GND
  PCIE_RX_DN0  = P3E_CPU1_PE3_MP_RXP<8>
  PCIE_RX_DP3  = P3E_CPU1_PE3_MP_RXN<11>
  PCIE_RX_DN6  = P3E_CPU1_PE3_MP_RXN<14>
  FAN_TACH2  = TP_FM_WAKE_N
  MNG_TX_DN  = IRQ_BOARD_BMC_ALERT_N
  PMBUS_DATA  = SMB_PEHPCPU1_STBY_LVC3_SDA
  PCIE_TX_DN3  = P3E_CPU1_PE3_MP_C_TXP<11>
  PCIE_TX_DP0  = P3E_CPU1_PE3_MP_C_TXN<8>
  GND3  = GND
  PCIE_RX_DN3  = P3E_CPU1_PE3_MP_RXP<11>
  GND4  = GND
  FAN_TACH1  = FM_BB_BMC_MP_GPIO
  GND5  = GND
  PMBUS_CLK  = SMB_PEHPCPU1_STBY_LVC3_SCL
  GND6  = GND
  PCIE_TX_DN0  = P3E_CPU1_PE3_MP_C_TXP<8>
  PCIE_RX_DP1  = P3E_CPU1_PE3_MP_RXN<9>
  GND7  = GND
  PCIE_RX_DP7  = P3E_CPU1_PE3_MP_RXN<15>
  FAN_TACH0  = GND
  MNG_RX_DP  = SMB_LAN_STBY_LVC3_SDA
  GND8  = GND
  PCIE_TX_DP4  = P3E_CPU1_PE3_MP_C_TXN<12>
  GND9  = GND
  PCIE_RX_DN1  = P3E_CPU1_PE3_MP_RXP<9>
  PCIE_RX_DP4  = P3E_CPU1_PE3_MP_RXN<12>
  PCIE_RX_DN7  = P3E_CPU1_PE3_MP_RXP<15>
  \mated_in#\  = TP_IOE4
  MNG_RX_DN  = SMB_LAN_STBY_LVC3_SCL
  PCIE_TX_DP6  = P3E_CPU1_PE3_MP_C_TXN<14>
  PCIE_TX_DN4  = P3E_CPU1_PE3_MP_C_TXP<12>
  PCIE_TX_DP1  = P3E_CPU1_PE3_MP_C_TXN<9>
  GND10  = GND
  PCIE_RX_DN4  = P3E_CPU1_PE3_MP_RXP<12>
  GND11  = GND
  FAN_PWM0  = TP_IOF4
  MB_SLOT_ID0  = GND
  PCIE_TX_DN6  = P3E_CPU1_PE3_MP_C_TXP<14>
  GND12  = GND
  PCIE_TX_DN1  = P3E_CPU1_PE3_MP_C_TXP<9>
  PCIE_RX_DP2  = P3E_CPU1_PE3_MP_RXP<10>
  GND13  = GND
  COM_TX  = TP_IOG3
  GND14  = GND
  MB_SLOT_ID1  = FM_XRC_PRESENT_N
  GND15  = GND
  PCIE_TX_DP5  = P3E_CPU1_PE3_MP_C_TXN<13>
  GND16  = GND
  PCIE_RX_DN2  = P3E_CPU1_PE3_MP_RXN<10>
  PCIE_RX_DP5  = P3E_CPU1_PE3_MP_RXP<13>
  COM_RX  = TP_IOH3
  PCIE_CLK_100M_DP  = TP_IOH4
  MB_SLOT_ID2  = FM_XRC_READY_N
  PCIE_TX_DP7  = P3E_CPU1_PE3_MP_C_TXN<15>
  PCIE_TX_DN5  = P3E_CPU1_PE3_MP_C_TXP<13>
  PCIE_TX_DP2  = P3E_CPU1_PE3_MP_C_TXP<10>
  GND17  = GND
  PCIE_RX_DN5  = P3E_CPU1_PE3_MP_RXN<13>
  \mb_on#\  = GND
  PCIE_CLK_100M_DN  = TP_IOI4
  \pcie_perst#\  = GND
  PCIE_TX_DN7  = P3E_CPU1_PE3_MP_C_TXP<15>
  GND18  = GND
  PCIE_TX_DN2  = P3E_CPU1_PE3_MP_C_TXN<10>
  J2  = GND
  J4  = GND
  J6  = GND
  J8  = GND

(kicad_pcb
	(version 20260206)
	(generator "pcbnew")
	(generator_version "10.0")
	(general
		(thickness 1.6)
		(legacy_teardrops no)
	)
	(paper "A4")
	(title_block
		(title "Wiwynn_Tioga_Pass_MB.brd")
		(comment 1 "Tioga Pass / footprint 1357 of 4770 (J1C1), pads 1-29 of 76")
	)
	(layers
		(0 "F.Cu" signal "TOP")
		(4 "In1.Cu" signal "L2GND")
		(6 "In2.Cu" signal "L3")
		(8 "In3.Cu" signal "L4GND")
		(10 "In4.Cu" signal "L5")
		(12 "In5.Cu" signal "L6GND")
		(14 "In6.Cu" signal "L7VCC")
		(16 "In7.Cu" signal "L8VCC")
		(18 "In8.Cu" signal "L9GND")
		(20 "In9.Cu" signal "L10")
		(22 "In10.Cu" signal "L11GND")
		(24 "In11.Cu" signal "L12")
		(26 "In12.Cu" signal "L13GND")
		(2 "B.Cu" signal "BOTTOM")
		(9 "F.Adhes" user "F.Adhesive")
		(11 "B.Adhes" user "B.Adhesive")
		(13 "F.Paste" user "Package Geometry/Pastemask Top")
		(15 "B.Paste" user "Package Geometry/Pastemask Bottom")
		(5 "F.SilkS" user "Ref Des/Silkscreen Top")
		(7 "B.SilkS" user "Ref Des/Silkscreen Bottom")
		(1 "F.Mask" user "Board Geometry/Soldermask Top")
		(3 "B.Mask" user "Board Geometry/Soldermask Bottom")
		(17 "Dwgs.User" user "User.Drawings")
		(19 "Cmts.User" user "User.Comments")
		(21 "Eco1.User" user "User.Eco1")
		(23 "Eco2.User" user "User.Eco2")
		(25 "Edge.Cuts" user "Board Geometry/Outline")
		(27 "Margin" user)
		(31 "F.CrtYd" user "Package Geometry/Place Bound Top")
		(29 "B.CrtYd" user "Package Geometry/Place Bound Bottom")
		(35 "F.Fab" user "Ref Des/Assembly Top")
		(33 "B.Fab" user "Ref Des/Assembly Bottom")
	)
	(footprint ""
		(layer "F.Cu")
		(at 2.29997 -97.769934 -90)
		(property "Reference" "J1C1"
			(at 0 0 270)
			(layer "F.SilkS")
			(hide yes)
			(effects
				(font
					(size 1.27 1.27)
				)
			)
		)
		(property "Value" "*"
			(at -20.8026 -3.4036 270)
			(unlocked yes)
			(layer "F.Fab")
			(hide yes)
			(effects
				(font
					(size 1.27 1.016)
					(thickness 0.1524)
				)
			)
		)
		(property "Device Type" "DM-FCI-CONN76-8R-GP-U-01_CONN-A"
			(at -20.8026 -4.9276 270)
			(unlocked yes)
			(layer "F.Fab")
			(hide yes)
			(effects
				(font
					(size 1.27 1.016)
					(thickness 0.1524)
				)
			)
		)
		(duplicate_pad_numbers_are_jumpers no)
		(pad "A1" thru_hole circle
			(at -6.999986 6.199886 270)
			(size 0.8128 0.8128)
			(drill 0.399796)
			(layers "*.Cu" "*.Mask")
			(remove_unused_layers no)
			(net "P3E_CPU1_PE3_MP_RXN<8>")
			(clearance 0.2921)
			(thermal_gap 0.2921)
		)
		(pad "A2" thru_hole circle
			(at -4.99999 6.299962 270)
			(size 0.8636 0.8636)
			(drill 0.499872)
			(layers "*.Cu" "*.Mask")
			(remove_unused_layers no)
			(net "GND")
			(clearance 0.1778)
			(thermal_gap 0.1778)
		)
		(pad "A3" thru_hole circle
			(at -2.999994 6.199886 270)
			(size 0.8128 0.8128)
			(drill 0.399796)
			(layers "*.Cu" "*.Mask")
			(remove_unused_layers no)
			(net "P3E_CPU1_PE3_MP_RXP<14>")
			(clearance 0.2921)
			(thermal_gap 0.2921)
		)
		(pad "A4" thru_hole circle
			(at -0.999998 6.299962 270)
			(size 0.8636 0.8636)
			(drill 0.499872)
			(layers "*.Cu" "*.Mask")
			(remove_unused_layers no)
			(net "GND")
			(clearance 0.1778)
			(thermal_gap 0.1778)
		)
		(pad "A5" thru_hole circle
			(at 0.999998 6.199886 270)
			(size 0.8128 0.8128)
			(drill 0.399796)
			(layers "*.Cu" "*.Mask")
			(remove_unused_layers no)
			(net "TP_IOA5")
			(clearance 0.2921)
			(thermal_gap 0.2921)
		)
		(pad "A6" thru_hole circle
			(at 2.999994 6.299962 270)
			(size 0.8636 0.8636)
			(drill 0.499872)
			(layers "*.Cu" "*.Mask")
			(remove_unused_layers no)
			(net "GND")
			(clearance 0.1778)
			(thermal_gap 0.1778)
		)
		(pad "A7" thru_hole circle
			(at 4.99999 6.199886 270)
			(size 0.8128 0.8128)
			(drill 0.399796)
			(layers "*.Cu" "*.Mask")
			(remove_unused_layers no)
			(net "P3E_CPU1_PE3_MP_C_TXN<11>")
			(clearance 0.2921)
			(thermal_gap 0.2921)
		)
		(pad "A8" thru_hole circle
			(at 6.999986 6.299962 270)
			(size 0.8636 0.8636)
			(drill 0.499872)
			(layers "*.Cu" "*.Mask")
			(remove_unused_layers no)
			(net "GND")
			(clearance 0.1778)
			(thermal_gap 0.1778)
		)
		(pad "B1" thru_hole circle
			(at -6.999986 4.800092 270)
			(size 0.8128 0.8128)
			(drill 0.399796)
			(layers "*.Cu" "*.Mask")
			(remove_unused_layers no)
			(net "P3E_CPU1_PE3_MP_RXP<8>")
			(clearance 0.2921)
			(thermal_gap 0.2921)
		)
		(pad "B2" thru_hole circle
			(at -4.99999 4.899914 270)
			(size 0.8128 0.8128)
			(drill 0.399796)
			(layers "*.Cu" "*.Mask")
			(remove_unused_layers no)
			(net "P3E_CPU1_PE3_MP_RXN<11>")
			(clearance 0.2921)
			(thermal_gap 0.2921)
		)
		(pad "B3" thru_hole circle
			(at -2.999994 4.800092 270)
			(size 0.8128 0.8128)
			(drill 0.399796)
			(layers "*.Cu" "*.Mask")
			(remove_unused_layers no)
			(net "P3E_CPU1_PE3_MP_RXN<14>")
			(clearance 0.2921)
			(thermal_gap 0.2921)
		)
		(pad "B4" thru_hole circle
			(at -0.999998 4.899914 270)
			(size 0.8128 0.8128)
			(drill 0.399796)
			(layers "*.Cu" "*.Mask")
			(remove_unused_layers no)
			(net "TP_FM_WAKE_N")
			(clearance 0.1524)
			(thermal_gap 0.1524)
		)
		(pad "B5" thru_hole circle
			(at 0.999998 4.800092 270)
			(size 0.8128 0.8128)
			(drill 0.399796)
			(layers "*.Cu" "*.Mask")
			(remove_unused_layers no)
			(net "IRQ_BOARD_BMC_ALERT_N")
			(clearance 0.2921)
			(thermal_gap 0.2921)
		)
		(pad "B6" thru_hole circle
			(at 2.999994 4.899914 270)
			(size 0.8128 0.8128)
			(drill 0.399796)
			(layers "*.Cu" "*.Mask")
			(remove_unused_layers no)
			(net "SMB_PEHPCPU1_STBY_LVC3_SDA")
			(clearance 0.1524)
			(thermal_gap 0.1524)
		)
		(pad "B7" thru_hole circle
			(at 4.99999 4.800092 270)
			(size 0.8128 0.8128)
			(drill 0.399796)
			(layers "*.Cu" "*.Mask")
			(remove_unused_layers no)
			(net "P3E_CPU1_PE3_MP_C_TXP<11>")
			(clearance 0.2921)
			(thermal_gap 0.2921)
		)
		(pad "B8" thru_hole circle
			(at 6.999986 4.899914 270)
			(size 0.8128 0.8128)
			(drill 0.399796)
			(layers "*.Cu" "*.Mask")
			(remove_unused_layers no)
			(net "P3E_CPU1_PE3_MP_C_TXN<8>")
			(clearance 0.2921)
			(thermal_gap 0.2921)
		)
		(pad "C1" thru_hole circle
			(at -6.999986 3.400044 270)
			(size 0.8636 0.8636)
			(drill 0.499872)
			(layers "*.Cu" "*.Mask")
			(remove_unused_layers no)
			(net "GND")
			(clearance 0.1778)
			(thermal_gap 0.1778)
		)
		(pad "C2" thru_hole circle
			(at -4.99999 3.50012 270)
			(size 0.8128 0.8128)
			(drill 0.399796)
			(layers "*.Cu" "*.Mask")
			(remove_unused_layers no)
			(net "P3E_CPU1_PE3_MP_RXP<11>")
			(clearance 0.2921)
			(thermal_gap 0.2921)
		)
		(pad "C3" thru_hole circle
			(at -2.999994 3.400044 270)
			(size 0.8636 0.8636)
			(drill 0.499872)
			(layers "*.Cu" "*.Mask")
			(remove_unused_layers no)
			(net "GND")
			(clearance 0.1778)
			(thermal_gap 0.1778)
		)
		(pad "C4" thru_hole circle
			(at -0.999998 3.50012 270)
			(size 0.8128 0.8128)
			(drill 0.399796)
			(layers "*.Cu" "*.Mask")
			(remove_unused_layers no)
			(net "FM_BB_BMC_MP_GPIO")
			(clearance 0.1524)
			(thermal_gap 0.1524)
		)
		(pad "C5" thru_hole circle
			(at 0.999998 3.400044 270)
			(size 0.8636 0.8636)
			(drill 0.499872)
			(layers "*.Cu" "*.Mask")
			(remove_unused_layers no)
			(net "GND")
			(clearance 0.1778)
			(thermal_gap 0.1778)
		)
		(pad "C6" thru_hole circle
			(at 2.999994 3.50012 270)
			(size 0.8128 0.8128)
			(drill 0.399796)
			(layers "*.Cu" "*.Mask")
			(remove_unused_layers no)
			(net "SMB_PEHPCPU1_STBY_LVC3_SCL")
			(clearance 0.1524)
			(thermal_gap 0.1524)
		)
		(pad "C7" thru_hole circle
			(at 4.99999 3.400044 270)
			(size 0.8636 0.8636)
			(drill 0.499872)
			(layers "*.Cu" "*.Mask")
			(remove_unused_layers no)
			(net "GND")
			(clearance 0.1778)
			(thermal_gap 0.1778)
		)
		(pad "C8" thru_hole circle
			(at 6.999986 3.50012 270)
			(size 0.8128 0.8128)
			(drill 0.399796)
			(layers "*.Cu" "*.Mask")
			(remove_unused_layers no)
			(net "P3E_CPU1_PE3_MP_C_TXP<8>")
			(clearance 0.2921)
			(thermal_gap 0.2921)
		)
		(pad "D1" thru_hole circle
			(at -6.999986 1.999996 270)
			(size 0.8128 0.8128)
			(drill 0.399796)
			(layers "*.Cu" "*.Mask")
			(remove_unused_layers no)
			(net "P3E_CPU1_PE3_MP_RXN<9>")
			(clearance 0.2921)
			(thermal_gap 0.2921)
		)
		(pad "D2" thru_hole circle
			(at -4.99999 2.100072 270)
			(size 0.8636 0.8636)
			(drill 0.499872)
			(layers "*.Cu" "*.Mask")
			(remove_unused_layers no)
			(net "GND")
			(clearance 0.1778)
			(thermal_gap 0.1778)
		)
		(pad "D3" thru_hole circle
			(at -2.999994 1.999996 270)
			(size 0.8128 0.8128)
			(drill 0.399796)
			(layers "*.Cu" "*.Mask")
			(remove_unused_layers no)
			(net "P3E_CPU1_PE3_MP_RXN<15>")
			(clearance 0.2921)
			(thermal_gap 0.2921)
		)
		(pad "D4" thru_hole circle
			(at -0.999998 2.100072 270)
			(size 0.8636 0.8636)
			(drill 0.499872)
			(layers "*.Cu" "*.Mask")
			(remove_unused_layers no)
			(net "GND")
			(clearance 0.1778)
			(thermal_gap 0.1778)
		)
		(pad "D5" thru_hole circle
			(at 0.999998 1.999996 270)
			(size 0.8128 0.8128)
			(drill 0.399796)
			(layers "*.Cu" "*.Mask")
			(remove_unused_layers no)
			(net "SMB_LAN_STBY_LVC3_SDA")
			(clearance 0.2921)
			(thermal_gap 0.2921)
		)
	)
)
